FILE_TYPE = MACRO_DRAWING;
SET COLOR_WIRE YELLOW;
SET COLOR_PROP MONO;
SET COLOR_DOT WHITE;
SET COLOR_ARC YELLOW;
SET COLOR_BODY GREEN;
SET COLOR_NOTE MONO;
SET PROP_DISPLAY VALUE;
SET PAGE_NUMBER P171;
FORCEADD INTEL_CORP_BPAGE..1
(2650 500);
FORCEPROP 1 LAST CDS_CON_LAST_MODIFIED Fri Jun 16 17:49:03 2017
J 0
(1225 825);
PAINT ORANGE (1225 825);
DISPLAY INVISIBLE (1225 825);
FORCEPROP 1 LAST CUSTOM_TXT_CDS <CURRENT_DESIGN_SHEET> OF <TOTAL_DESIGN_SHEETS>
J 0
(2150 525);
PAINT ORANGE (2150 525);
FORCEPROP 1 LAST CUSTOM_TXT_CDS <CON_LAST_MODIFIED>
J 0
(-1350 600);
PAINT ORANGE (-1350 600);
FORCEPROP 2 LAST CUSTOM_TXT_CDS <XR_PAGE_TITLE>
J 0
(-5240 5750);
DISPLAY 0.638298 (-5240 5750);
PAINT PINK (-5240 5750);
DISPLAY INVISIBLE (-5240 5750);
FORCEPROP 1 LAST SCH_TITLE SPARE
J 0
(-5300 550);
DISPLAY 1.212766 (-5300 550);
PAINT ORANGE (-5300 550);
FORCEPROP 2 LAST PAGE_BORDER TRUE
J 0
(-5240 5750);
DISPLAY 0.851064 (-5240 5750);
PAINT PINK (-5240 5750);
DISPLAY INVISIBLE (-5240 5750);
FORCEPROP 2 LAST CDS_LIB mstr_symbols
J 0
(2650 500);
PAINT MONO (2650 500);
DISPLAY INVISIBLE (2650 500);
FORCEPROP 1 LAST COMMENT_BODY TRUE
J 0
(2662 512);
DISPLAY 0.468085 (2662 512);
PAINT GREEN (2662 512);
DISPLAY INVISIBLE (2662 512);
FORCEPROP 2 LAST CDS_XR_PAGE_TITLE CR-171 : @BASEBOARD_FAB2_LIB.BASEBOARD_FAB2(SCH_1):PAGE171
J 0
(-5240 5750);
DISPLAY 0.638298 (-5240 5750);
PAINT PINK (-5240 5750);
DISPLAY INVISIBLE (-5240 5750);
QUIT
